(kicad_pcb
	(version 20241229)
	(generator "pcbnew")
	(generator_version "9.0")
	(general
		(thickness 1.61)
		(legacy_teardrops no)
	)
	(paper "A3")
	(title_block
		(title "RDIMM DDR5 Tester")
		(date "2026-05-21")
		(rev "2.2.0")
		(company "Antmicro")
		(comment 9 "footprints 71-76 of 796")
	)
	(layers
		(0 "F.Cu" signal)
		(4 "In1.Cu" power)
		(6 "In2.Cu" mixed)
		(8 "In3.Cu" power)
		(10 "In4.Cu" mixed)
		(12 "In5.Cu" power)
		(14 "In6.Cu" mixed)
		(16 "In7.Cu" power)
		(18 "In8.Cu" power)
		(20 "In9.Cu" mixed)
		(22 "In10.Cu" power)
		(2 "B.Cu" signal)
		(9 "F.Adhes" user "F.Adhesive")
		(11 "B.Adhes" user "B.Adhesive")
		(13 "F.Paste" user)
		(15 "B.Paste" user)
		(5 "F.SilkS" user "F.Silkscreen")
		(7 "B.SilkS" user "B.Silkscreen")
		(1 "F.Mask" user)
		(3 "B.Mask" user)
		(17 "Dwgs.User" user "User.Drawings")
		(19 "Cmts.User" user "User.Comments")
		(21 "Eco1.User" user "User.Eco1")
		(23 "Eco2.User" user "User.Eco2")
		(25 "Edge.Cuts" user)
		(27 "Margin" user)
		(31 "F.CrtYd" user "F.Courtyard")
		(29 "B.CrtYd" user "B.Courtyard")
		(35 "F.Fab" user)
		(33 "B.Fab" user)
	)
	(footprint "antmicro-footprints:C_0402_1005Metric"
		(layer "F.Cu")
		(at 257.79 145.385 -90)
		(descr "Capacitor SMD 0402")
		(tags "capacitor SMD 0402")
		(property "Reference" "C127"
			(at -0.985 0.54 90)
			(layer "F.SilkS")
			(effects
				(font
					(size 0.7 0.7)
					(thickness 0.15)
				)
				(justify right bottom)
			)
		)
		(property "Value" "C_1u_0402"
			(at -1.022927 2.155213 90)
			(layer "F.Fab")
			(effects
				(font
					(size 0.7 0.7)
					(thickness 0.15)
				)
				(justify right bottom)
			)
		)
		(property "Datasheet" "https://product.tdk.com/en/search/capacitor/ceramic/mlcc/info?part_no=C1005X6S1A105K050BC"
			(at 0 0 90)
			(layer "F.Fab")
			(hide yes)
			(effects
				(font
					(size 1.27 1.27)
					(thickness 0.15)
				)
			)
		)
		(property "Manufacturer" "TDK"
			(at 0 0 270)
			(unlocked yes)
			(layer "F.Fab")
			(hide yes)
			(effects
				(font
					(size 1 1)
					(thickness 0.15)
				)
			)
		)
		(property "MPN" "C1005X6S1A105K050BC"
			(at 0 0 270)
			(unlocked yes)
			(layer "F.Fab")
			(hide yes)
			(effects
				(font
					(size 1 1)
					(thickness 0.15)
				)
			)
		)
		(property "Val" "1u"
			(at 0 0 270)
			(unlocked yes)
			(layer "F.Fab")
			(hide yes)
			(effects
				(font
					(size 1 1)
					(thickness 0.15)
				)
			)
		)
		(property "License" "Apache-2.0"
			(at 0 0 270)
			(unlocked yes)
			(layer "F.Fab")
			(hide yes)
			(effects
				(font
					(size 1 1)
					(thickness 0.15)
				)
			)
		)
		(property "Author" "Antmicro"
			(at 0 0 270)
			(unlocked yes)
			(layer "F.Fab")
			(hide yes)
			(effects
				(font
					(size 1 1)
					(thickness 0.15)
				)
			)
		)
		(property "Voltage" ""
			(at 0 0 270)
			(unlocked yes)
			(layer "F.Fab")
			(hide yes)
			(effects
				(font
					(size 1 1)
					(thickness 0.15)
				)
			)
		)
		(property "Dielectric" ""
			(at 0 0 270)
			(unlocked yes)
			(layer "F.Fab")
			(hide yes)
			(effects
				(font
					(size 1 1)
					(thickness 0.15)
				)
			)
		)
		(sheetname "/DDR5 RDIMM/")
		(sheetfile "ddr5-rdimm.kicad_sch")
		(attr smd exclude_from_bom dnp)
		(fp_rect
			(start -0.925 -0.47)
			(end 0.925 0.47)
			(stroke
				(width 0.05)
				(type default)
			)
			(fill no)
			(layer "F.CrtYd")
		)
		(fp_line
			(start -0.494 0.248)
			(end -0.494 -0.25)
			(stroke
				(width 0.15)
				(type solid)
			)
			(layer "F.Fab")
		)
		(fp_line
			(start 0.504 0.248)
			(end -0.494 0.248)
			(stroke
				(width 0.15)
				(type solid)
			)
			(layer "F.Fab")
		)
		(fp_line
			(start -0.494 -0.25)
			(end 0.504 -0.25)
			(stroke
				(width 0.15)
				(type solid)
			)
			(layer "F.Fab")
		)
		(fp_line
			(start 0.504 -0.25)
			(end 0.504 0.248)
			(stroke
				(width 0.15)
				(type solid)
			)
			(layer "F.Fab")
		)
		(fp_text user "Author: Antmicro"
			(at -0.939 3.399 270)
			(layer "F.Fab")
			(effects
				(font
					(size 0.7 0.7)
					(thickness 0.15)
				)
				(justify left bottom)
			)
		)
		(fp_text user "License: Apache-2.0"
			(at -0.939 5.799 270)
			(layer "F.Fab")
			(effects
				(font
					(size 0.7 0.7)
					(thickness 0.15)
				)
				(justify left bottom)
			)
		)
		(fp_text user "${REFERENCE}"
			(at -0.939 4.599 270)
			(layer "F.Fab")
			(effects
				(font
					(size 0.7 0.7)
					(thickness 0.15)
				)
				(justify left bottom)
			)
		)
		(pad "1" smd roundrect
			(at -0.48 0 270)
			(size 0.59 0.64)
			(layers "F.Cu" "F.Mask" "F.Paste")
			(roundrect_rratio 0.25)
			(net 69 "HOT_SWAP_BUTTON")
			(pintype "passive")
		)
		(pad "2" smd roundrect
			(at 0.48 0 270)
			(size 0.59 0.64)
			(layers "F.Cu" "F.Mask" "F.Paste")
			(roundrect_rratio 0.25)
			(net 1 "GND")
			(pintype "passive")
		)
	)
	(footprint "antmicro-footprints:F_1206_3216Metric"
		(layer "F.Cu")
		(at 250.4 124.4 -90)
		(property "Reference" "F1"
			(at -0.6 -2.25 90)
			(layer "F.SilkS")
			(effects
				(font
					(size 0.7 0.7)
					(thickness 0.15)
				)
				(justify right bottom)
			)
		)
		(property "Value" "F_4A_1206"
			(at 0 2 90)
			(layer "F.Fab")
			(effects
				(font
					(size 0.7 0.7)
					(thickness 0.15)
				)
				(justify right bottom)
			)
		)
		(property "Datasheet" "https://www.littelfuse.com/media?resourcetype=datasheets&itemid=dbe9bcd7-6072-4adf-bf5b-d33e52a6b90f&filename=littelfuse-fuse-466-datasheet"
			(at 0 0 90)
			(layer "F.Fab")
			(hide yes)
			(effects
				(font
					(size 1.27 1.27)
					(thickness 0.15)
				)
			)
		)
		(property "Manufacturer" "Littelfuse"
			(at 0 0 270)
			(unlocked yes)
			(layer "F.Fab")
			(hide yes)
			(effects
				(font
					(size 1 1)
					(thickness 0.15)
				)
			)
		)
		(property "MPN" "0466004.NR "
			(at 0 0 270)
			(unlocked yes)
			(layer "F.Fab")
			(hide yes)
			(effects
				(font
					(size 1 1)
					(thickness 0.15)
				)
			)
		)
		(property "Author" "Antmicro"
			(at 0 0 270)
			(unlocked yes)
			(layer "F.Fab")
			(hide yes)
			(effects
				(font
					(size 1 1)
					(thickness 0.15)
				)
			)
		)
		(property "License" "Apache-2.0"
			(at 0 0 270)
			(unlocked yes)
			(layer "F.Fab")
			(hide yes)
			(effects
				(font
					(size 1 1)
					(thickness 0.15)
				)
			)
		)
		(sheetname "/Supply/")
		(sheetfile "supply.kicad_sch")
		(attr smd)
		(fp_line
			(start 0.8 0.901)
			(end -0.8 0.901)
			(stroke
				(width 0.15)
				(type solid)
			)
			(layer "F.SilkS")
		)
		(fp_line
			(start 0.8 -0.899)
			(end -0.8 -0.899)
			(stroke
				(width 0.15)
				(type solid)
			)
			(layer "F.SilkS")
		)
		(fp_rect
			(start -2.325 -1.15)
			(end 2.325 1.15)
			(stroke
				(width 0.05)
				(type default)
			)
			(fill no)
			(layer "F.CrtYd")
		)
		(fp_line
			(start -1.677 0.792)
			(end -1.677 -0.861)
			(stroke
				(width 0.15)
				(type solid)
			)
			(layer "F.Fab")
		)
		(fp_line
			(start 1.624 0.792)
			(end -1.677 0.792)
			(stroke
				(width 0.15)
				(type solid)
			)
			(layer "F.Fab")
		)
		(fp_line
			(start -1.677 -0.861)
			(end 1.624 -0.861)
			(stroke
				(width 0.15)
				(type solid)
			)
			(layer "F.Fab")
		)
		(fp_line
			(start 1.624 -0.861)
			(end 1.624 0.792)
			(stroke
				(width 0.15)
				(type solid)
			)
			(layer "F.Fab")
		)
		(fp_text user "Author: Antmicro"
			(at -1.95 6.4 270)
			(layer "F.Fab")
			(effects
				(font
					(size 0.7 0.7)
					(thickness 0.15)
				)
				(justify left bottom)
			)
		)
		(fp_text user "${REFERENCE}"
			(at -1.95 4 270)
			(layer "F.Fab")
			(effects
				(font
					(size 0.7 0.7)
					(thickness 0.15)
				)
				(justify left bottom)
			)
		)
		(fp_text user "License: Apache-2.0"
			(at -1.95 5.2 270)
			(layer "F.Fab")
			(effects
				(font
					(size 0.7 0.7)
					(thickness 0.15)
				)
				(justify left bottom)
			)
		)
		(pad "1" smd roundrect
			(at -1.5 0.001 270)
			(size 1.15 1.8)
			(layers "F.Cu" "F.Mask" "F.Paste")
			(roundrect_rratio 0.25)
			(net 325 "/Supply/12V_aux")
			(pintype "passive")
		)
		(pad "2" smd roundrect
			(at 1.5 0.001 270)
			(size 1.15 1.8)
			(layers "F.Cu" "F.Mask" "F.Paste")
			(roundrect_rratio 0.25)
			(net 323 "/Supply/12V_aux_fused")
			(pintype "passive")
		)
	)
	(footprint "antmicro-footprints:C_0402_1005Metric"
		(layer "F.Cu")
		(at 243.047 124.356099)
		(descr "Capacitor SMD 0402")
		(tags "capacitor SMD 0402")
		(property "Reference" "C175"
			(at -3.826258 0.453901 0)
			(layer "F.SilkS")
			(effects
				(font
					(size 0.7 0.7)
					(thickness 0.15)
				)
				(justify left bottom)
			)
		)
		(property "Value" "C_100n_0402"
			(at -1.022927 2.155213 0)
			(layer "F.Fab")
			(effects
				(font
					(size 0.7 0.7)
					(thickness 0.15)
				)
				(justify left bottom)
			)
		)
		(property "Datasheet" "https://www.murata.com/products/productdetail?partno=GRM155R61H104KE14%23"
			(at 0 0 0)
			(layer "F.Fab")
			(hide yes)
			(effects
				(font
					(size 1.27 1.27)
					(thickness 0.15)
				)
			)
		)
		(property "Manufacturer" "Murata"
			(at 0 0 0)
			(unlocked yes)
			(layer "F.Fab")
			(hide yes)
			(effects
				(font
					(size 1 1)
					(thickness 0.15)
				)
			)
		)
		(property "MPN" "GRM155R61H104KE14D"
			(at 0 0 0)
			(unlocked yes)
			(layer "F.Fab")
			(hide yes)
			(effects
				(font
					(size 1 1)
					(thickness 0.15)
				)
			)
		)
		(property "Val" "100n"
			(at 0 0 0)
			(unlocked yes)
			(layer "F.Fab")
			(hide yes)
			(effects
				(font
					(size 1 1)
					(thickness 0.15)
				)
			)
		)
		(property "License" "Apache-2.0"
			(at 0 0 0)
			(unlocked yes)
			(layer "F.Fab")
			(hide yes)
			(effects
				(font
					(size 1 1)
					(thickness 0.15)
				)
			)
		)
		(property "Author" "Antmicro"
			(at 0 0 0)
			(unlocked yes)
			(layer "F.Fab")
			(hide yes)
			(effects
				(font
					(size 1 1)
					(thickness 0.15)
				)
			)
		)
		(property "Voltage" "50V"
			(at 0 0 0)
			(unlocked yes)
			(layer "F.Fab")
			(hide yes)
			(effects
				(font
					(size 1 1)
					(thickness 0.15)
				)
			)
		)
		(property "Dielectric" "X5R"
			(at 0 0 0)
			(unlocked yes)
			(layer "F.Fab")
			(hide yes)
			(effects
				(font
					(size 1 1)
					(thickness 0.15)
				)
			)
		)
		(sheetname "/Supply/")
		(sheetfile "supply.kicad_sch")
		(attr smd)
		(fp_rect
			(start -0.925 -0.47)
			(end 0.925 0.47)
			(stroke
				(width 0.05)
				(type default)
			)
			(fill no)
			(layer "F.CrtYd")
		)
		(fp_line
			(start -0.494 -0.25)
			(end 0.504 -0.25)
			(stroke
				(width 0.15)
				(type solid)
			)
			(layer "F.Fab")
		)
		(fp_line
			(start -0.494 0.248)
			(end -0.494 -0.25)
			(stroke
				(width 0.15)
				(type solid)
			)
			(layer "F.Fab")
		)
		(fp_line
			(start 0.504 -0.25)
			(end 0.504 0.248)
			(stroke
				(width 0.15)
				(type solid)
			)
			(layer "F.Fab")
		)
		(fp_line
			(start 0.504 0.248)
			(end -0.494 0.248)
			(stroke
				(width 0.15)
				(type solid)
			)
			(layer "F.Fab")
		)
		(fp_text user "Author: Antmicro"
			(at -0.939 3.399 0)
			(layer "F.Fab")
			(effects
				(font
					(size 0.7 0.7)
					(thickness 0.15)
				)
				(justify left bottom)
			)
		)
		(fp_text user "License: Apache-2.0"
			(at -0.939 5.799 0)
			(layer "F.Fab")
			(effects
				(font
					(size 0.7 0.7)
					(thickness 0.15)
				)
				(justify left bottom)
			)
		)
		(fp_text user "${REFERENCE}"
			(at -0.939 4.599 0)
			(layer "F.Fab")
			(effects
				(font
					(size 0.7 0.7)
					(thickness 0.15)
				)
				(justify left bottom)
			)
		)
		(pad "1" smd roundrect
			(at -0.48 0)
			(size 0.59 0.64)
			(layers "F.Cu" "F.Mask" "F.Paste")
			(roundrect_rratio 0.25)
			(net 1 "GND")
			(pintype "passive")
		)
		(pad "2" smd roundrect
			(at 0.48 0)
			(size 0.59 0.64)
			(layers "F.Cu" "F.Mask" "F.Paste")
			(roundrect_rratio 0.25)
			(net 323 "/Supply/12V_aux_fused")
			(pintype "passive")
		)
	)
	(footprint "antmicro-footprints:C_0603_1608Metric"
		(layer "F.Cu")
		(at 250.35 171.372001 90)
		(descr "Capacitor SMD 0603")
		(tags "capacitor 0603")
		(property "Reference" "C188"
			(at 1.272001 0.35 90)
			(layer "F.SilkS")
			(effects
				(font
					(size 0.7 0.7)
					(thickness 0.15)
				)
				(justify left bottom)
			)
		)
		(property "Value" "C_22u_0603"
			(at -1.42757 1.770288 90)
			(layer "F.Fab")
			(effects
				(font
					(size 0.7 0.7)
					(thickness 0.15)
				)
				(justify left bottom)
			)
		)
		(property "Datasheet" "https://www.murata.com/products/productdetail?partno=GRM188R60J226MEA0%23"
			(at 0 0 90)
			(layer "F.Fab")
			(hide yes)
			(effects
				(font
					(size 1.27 1.27)
					(thickness 0.15)
				)
			)
		)
		(property "Manufacturer" "Murata"
			(at 0 0 90)
			(unlocked yes)
			(layer "F.Fab")
			(hide yes)
			(effects
				(font
					(size 1 1)
					(thickness 0.15)
				)
			)
		)
		(property "MPN" "GRM188R60J226MEA0D"
			(at 0 0 90)
			(unlocked yes)
			(layer "F.Fab")
			(hide yes)
			(effects
				(font
					(size 1 1)
					(thickness 0.15)
				)
			)
		)
		(property "Val" "22u"
			(at 0 0 90)
			(unlocked yes)
			(layer "F.Fab")
			(hide yes)
			(effects
				(font
					(size 1 1)
					(thickness 0.15)
				)
			)
		)
		(property "License" "Apache-2.0"
			(at 0 0 90)
			(unlocked yes)
			(layer "F.Fab")
			(hide yes)
			(effects
				(font
					(size 1 1)
					(thickness 0.15)
				)
			)
		)
		(property "Author" "Antmicro"
			(at 0 0 90)
			(unlocked yes)
			(layer "F.Fab")
			(hide yes)
			(effects
				(font
					(size 1 1)
					(thickness 0.15)
				)
			)
		)
		(property "Voltage" ""
			(at 0 0 90)
			(unlocked yes)
			(layer "F.Fab")
			(hide yes)
			(effects
				(font
					(size 1 1)
					(thickness 0.15)
				)
			)
		)
		(property "Dielectric" ""
			(at 0 0 90)
			(unlocked yes)
			(layer "F.Fab")
			(hide yes)
			(effects
				(font
					(size 1 1)
					(thickness 0.15)
				)
			)
		)
		(sheetname "/Supply/DC-DC AUX, MGT/")
		(sheetfile "dc-dc-aux-mgt.kicad_sch")
		(attr smd)
		(fp_line
			(start -0.15 -0.4)
			(end 0.15 -0.4)
			(stroke
				(width 0.15)
				(type solid)
			)
			(layer "F.SilkS")
		)
		(fp_line
			(start -0.15 0.4)
			(end 0.15 0.4)
			(stroke
				(width 0.15)
				(type solid)
			)
			(layer "F.SilkS")
		)
		(fp_rect
			(start -1.25 -0.65)
			(end 1.25 0.65)
			(stroke
				(width 0.05)
				(type solid)
			)
			(fill no)
			(layer "F.CrtYd")
		)
		(fp_rect
			(start -0.8 -0.4)
			(end 0.8 0.4)
			(stroke
				(width 0.15)
				(type solid)
			)
			(fill no)
			(layer "F.Fab")
		)
		(fp_text user "${REFERENCE}"
			(at -1.682 3.895 90)
			(layer "F.Fab")
			(effects
				(font
					(size 0.7 0.7)
					(thickness 0.15)
				)
				(justify left bottom)
			)
		)
		(fp_text user "License: Apache-2.0"
			(at -1.682 5.895 90)
			(layer "F.Fab")
			(effects
				(font
					(size 0.7 0.7)
					(thickness 0.15)
				)
				(justify left bottom)
			)
		)
		(fp_text user "Author: Antmicro"
			(at -1.682 4.894 90)
			(layer "F.Fab")
			(effects
				(font
					(size 0.7 0.7)
					(thickness 0.15)
				)
				(justify left bottom)
			)
		)
		(pad "1" smd roundrect
			(at -0.7 0 90)
			(size 0.8 1)
			(layers "F.Cu" "F.Mask" "F.Paste")
			(roundrect_rratio 0.2)
			(net 1 "GND")
			(pintype "passive")
		)
		(pad "2" smd roundrect
			(at 0.7 0 90)
			(size 0.8 1)
			(layers "F.Cu" "F.Mask" "F.Paste")
			(roundrect_rratio 0.2)
			(net 48 "/Supply/DC-DC AUX, MGT/MGTAVTT_local")
			(pintype "passive")
		)
	)
	(footprint "antmicro-footprints:TP_SMD_1mm"
		(layer "F.Cu")
		(at 244.025 161.95)
		(property "Reference" "TP11"
			(at 0 -0.731898 0)
			(layer "F.SilkS")
			(hide yes)
			(effects
				(font
					(size 0.7 0.7)
					(thickness 0.15)
				)
				(justify left bottom)
			)
		)
		(property "Value" "TP_1mm_SMD"
			(at 0 1.4 0)
			(layer "F.Fab")
			(effects
				(font
					(size 0.7 0.7)
					(thickness 0.15)
				)
				(justify left bottom)
			)
		)
		(property "MPN" ""
			(at 0 0 0)
			(unlocked yes)
			(layer "F.Fab")
			(hide yes)
			(effects
				(font
					(size 1 1)
					(thickness 0.15)
				)
			)
		)
		(property "Manufacturer" ""
			(at 0 0 0)
			(unlocked yes)
			(layer "F.Fab")
			(hide yes)
			(effects
				(font
					(size 1 1)
					(thickness 0.15)
				)
			)
		)
		(property "Author" "Antmicro"
			(at 0 0 0)
			(unlocked yes)
			(layer "F.Fab")
			(hide yes)
			(effects
				(font
					(size 1 1)
					(thickness 0.15)
				)
			)
		)
		(property "License" "Apache-2.0"
			(at 0 0 0)
			(unlocked yes)
			(layer "F.Fab")
			(hide yes)
			(effects
				(font
					(size 1 1)
					(thickness 0.15)
				)
			)
		)
		(sheetname "/Supply/DC-DC IO/")
		(sheetfile "dc-dc-io.kicad_sch")
		(attr exclude_from_pos_files)
		(fp_circle
			(center 0 0)
			(end 0.6 0)
			(stroke
				(width 0.05)
				(type default)
			)
			(fill no)
			(layer "F.CrtYd")
		)
		(fp_text user "Author: Antmicro"
			(at -0.5 4 0)
			(layer "F.Fab")
			(effects
				(font
					(size 0.7 0.7)
					(thickness 0.15)
				)
				(justify left bottom)
			)
		)
		(fp_text user "License: Apache-2.0"
			(at -0.5 5.2 0)
			(layer "F.Fab")
			(effects
				(font
					(size 0.7 0.7)
					(thickness 0.15)
				)
				(justify left bottom)
			)
		)
		(fp_text user "${REFERENCE}"
			(at -0.5 2.8 0)
			(layer "F.Fab")
			(effects
				(font
					(size 0.7 0.7)
					(thickness 0.15)
				)
				(justify left bottom)
			)
		)
		(pad "1" smd circle
			(at 0 0)
			(size 1 1)
			(layers "F.Cu" "F.Mask")
			(net 150 "+1V2")
			(pinfunction "1")
			(pintype "passive")
		)
	)
	(footprint "antmicro-footprints:R_0402_1005Metric"
		(layer "F.Cu")
		(at 225.881 180.65 -90)
		(descr "Resistor SMD 0402")
		(tags "resistor SMD 0402")
		(property "Reference" "R198"
			(at 1.25 -0.399 90)
			(layer "F.SilkS")
			(effects
				(font
					(size 0.7 0.7)
					(thickness 0.15)
				)
				(justify right bottom)
			)
		)
		(property "Value" "R_10R_0402"
			(at -1.011843 1.772047 90)
			(layer "F.Fab")
			(effects
				(font
					(size 0.7 0.7)
					(thickness 0.15)
				)
				(justify right bottom)
			)
		)
		(property "Datasheet" "https://www.bourns.com/docs/product-datasheets/cr.pdf"
			(at 0 0 270)
			(layer "F.Fab")
			(hide yes)
			(effects
				(font
					(size 1.27 1.27)
					(thickness 0.15)
				)
			)
		)
		(property "MPN" "CR0402-FX-10R0GLF"
			(at 0 0 270)
			(unlocked yes)
			(layer "F.Fab")
			(hide yes)
			(effects
				(font
					(size 1 1)
					(thickness 0.15)
				)
			)
		)
		(property "Manufacturer" "Bourns"
			(at 0 0 270)
			(unlocked yes)
			(layer "F.Fab")
			(hide yes)
			(effects
				(font
					(size 1 1)
					(thickness 0.15)
				)
			)
		)
		(property "License" "Apache-2.0"
			(at 0 0 270)
			(unlocked yes)
			(layer "F.Fab")
			(hide yes)
			(effects
				(font
					(size 1 1)
					(thickness 0.15)
				)
			)
		)
		(property "Author" "Antmicro"
			(at 0 0 270)
			(unlocked yes)
			(layer "F.Fab")
			(hide yes)
			(effects
				(font
					(size 1 1)
					(thickness 0.15)
				)
			)
		)
		(property "Val" "10R"
			(at 0 0 270)
			(unlocked yes)
			(layer "F.Fab")
			(hide yes)
			(effects
				(font
					(size 1 1)
					(thickness 0.15)
				)
			)
		)
		(property "Tolerance" "1%"
			(at 0 0 270)
			(unlocked yes)
			(layer "F.Fab")
			(hide yes)
			(effects
				(font
					(size 1 1)
					(thickness 0.15)
				)
			)
		)
		(sheetname "/Supply/DC-DC VCCINT/")
		(sheetfile "dc-dc-vccint.kicad_sch")
		(attr smd)
		(fp_rect
			(start -0.925 -0.47)
			(end 0.925 0.47)
			(stroke
				(width 0.05)
				(type default)
			)
			(fill no)
			(layer "F.CrtYd")
		)
		(fp_rect
			(start -0.5 -0.25)
			(end 0.5 0.25)
			(stroke
				(width 0.15)
				(type solid)
			)
			(fill no)
			(layer "F.Fab")
		)
		(fp_text user "Author: Antmicro"
			(at -0.95 4.169 270)
			(layer "F.Fab")
			(effects
				(font
					(size 0.7 0.7)
					(thickness 0.15)
				)
				(justify left bottom)
			)
		)
		(fp_text user "${REFERENCE}"
			(at -0.95 3.168 270)
			(layer "F.Fab")
			(effects
				(font
					(size 0.7 0.7)
					(thickness 0.15)
				)
				(justify left bottom)
			)
		)
		(fp_text user "License: Apache-2.0"
			(at -0.95 5.169 270)
			(layer "F.Fab")
			(effects
				(font
					(size 0.7 0.7)
					(thickness 0.15)
				)
				(justify left bottom)
			)
		)
		(pad "1" smd roundrect
			(at -0.48 0 270)
			(size 0.59 0.64)
			(layers "F.Cu" "F.Mask" "F.Paste")
			(roundrect_rratio 0.25)
			(net 49 "Net-(U36-V_{DRV})")
			(pintype "passive")
		)
		(pad "2" smd roundrect
			(at 0.48 0 270)
			(size 0.59 0.64)
			(layers "F.Cu" "F.Mask" "F.Paste")
			(roundrect_rratio 0.25)
			(net 163 "/Supply/DC-DC VCCINT/V_{CC}")
			(pintype "passive")
		)
	)
)
